(kicad_pcb
	(version 20241229)
	(generator "pcbnew")
	(generator_version "9.0")
	(general
		(thickness 1.294)
		(legacy_teardrops no)
	)
	(paper "A3")
	(title_block
		(title "Kintex 410T devboard")
		(date "2024-04-03")
		(rev "1.1.2")
		(comment 9 "footprint 89 of 975 (J18), pads 271-358 of 564")
	)
	(layers
		(0 "F.Cu" mixed)
		(4 "In1.Cu" power)
		(6 "In2.Cu" power)
		(8 "In3.Cu" mixed)
		(10 "In4.Cu" power)
		(12 "In5.Cu" mixed)
		(14 "In6.Cu" power)
		(16 "In7.Cu" mixed)
		(18 "In8.Cu" power)
		(2 "B.Cu" mixed)
		(9 "F.Adhes" user "F.Adhesive")
		(11 "B.Adhes" user "B.Adhesive")
		(13 "F.Paste" user)
		(15 "B.Paste" user)
		(5 "F.SilkS" user "F.Silkscreen")
		(7 "B.SilkS" user "B.Silkscreen")
		(1 "F.Mask" user)
		(3 "B.Mask" user)
		(17 "Dwgs.User" user "User.Drawings")
		(19 "Cmts.User" user "User.Comments")
		(21 "Eco1.User" user "User.Eco1")
		(23 "Eco2.User" user "User.Eco2")
		(25 "Edge.Cuts" user)
		(27 "Margin" user)
		(31 "F.CrtYd" user "F.Courtyard")
		(29 "B.CrtYd" user "B.Courtyard")
		(35 "F.Fab" user)
		(33 "B.Fab" user)
	)
	(footprint "antmicro-footprints:ASP-184329-01_mounting_holes"
		(layer "F.Cu")
		(at 162.000001 106.000001 90)
		(property "Reference" "J18"
			(at 28.280001 4.299999 180)
			(layer "F.SilkS")
			(effects
				(font
					(size 0.7 0.7)
					(thickness 0.15)
				)
				(justify left bottom)
			)
		)
		(property "Value" "ASP-184329-01_mounting_holes"
			(at -8.4 0.2 90)
			(layer "F.Fab")
			(effects
				(font
					(size 0.7 0.7)
					(thickness 0.15)
				)
				(justify left bottom)
			)
		)
		(property "Description" "Mezzanine Connector, Array, Female, 1.27 mm, 14 Rows, 560 Contacts, Surface Mount"
			(at 0 0 90)
			(layer "F.Fab")
			(hide yes)
			(effects
				(font
					(size 1.27 1.27)
					(thickness 0.15)
				)
			)
		)
		(property "Author" "Antmicro"
			(at 268.000002 -56 0)
			(layer "F.Fab")
			(hide yes)
			(effects
				(font
					(size 1 1)
					(thickness 0.15)
				)
			)
		)
		(property "License" "Apache-2.0"
			(at 268.000002 -56 0)
			(layer "F.Fab")
			(hide yes)
			(effects
				(font
					(size 1 1)
					(thickness 0.15)
				)
			)
		)
		(property "MPN" "ASP-184329-01"
			(at 268.000002 -56 0)
			(layer "F.Fab")
			(hide yes)
			(effects
				(font
					(size 1 1)
					(thickness 0.15)
				)
			)
		)
		(property "Manufacturer" "Samtec"
			(at 268.000002 -56 0)
			(layer "F.Fab")
			(hide yes)
			(effects
				(font
					(size 1 1)
					(thickness 0.15)
				)
			)
		)
		(sheetname "FMC+ HSPC")
		(sheetfile "fmc-hspc.kicad_sch")
		(attr smd)
		(pad "G27" smd circle
			(at -8.257 -1.905 90)
			(size 0.64 0.64)
			(layers "F.Cu" "F.Mask")
			(net 392 "/FMC+ HSPC/FMC.IO8_P")
			(pinfunction "LA25_P")
			(pintype "passive")
		)
		(pad "G28" smd circle
			(at -9.526 -1.905 90)
			(size 0.64 0.64)
			(layers "F.Cu" "F.Mask")
			(net 388 "/FMC+ HSPC/FMC.IO8_N")
			(pinfunction "LA25_N")
			(pintype "passive")
		)
		(pad "G29" smd circle
			(at -10.795 -1.905 90)
			(size 0.64 0.64)
			(layers "F.Cu" "F.Mask")
			(net 1 "GND")
			(pinfunction "GND")
			(pintype "passive")
		)
		(pad "G30" smd circle
			(at -12.065 -1.905 90)
			(size 0.64 0.64)
			(layers "F.Cu" "F.Mask")
			(net 381 "/FMC+ HSPC/FMC.IO9_P")
			(pinfunction "LA29_P")
			(pintype "passive")
		)
		(pad "G31" smd circle
			(at -13.337 -1.905 90)
			(size 0.64 0.64)
			(layers "F.Cu" "F.Mask")
			(net 377 "/FMC+ HSPC/FMC.IO9_N")
			(pinfunction "LA29_N")
			(pintype "passive")
		)
		(pad "G32" smd circle
			(at -14.606 -1.905 90)
			(size 0.64 0.64)
			(layers "F.Cu" "F.Mask")
			(net 1 "GND")
			(pinfunction "GND")
			(pintype "passive")
		)
		(pad "G33" smd circle
			(at -15.875 -1.905 90)
			(size 0.64 0.64)
			(layers "F.Cu" "F.Mask")
			(net 373 "/FMC+ HSPC/FMC.IO0")
			(pinfunction "LA31_P")
			(pintype "passive")
		)
		(pad "G34" smd circle
			(at -17.145 -1.905 90)
			(size 0.64 0.64)
			(layers "F.Cu" "F.Mask")
			(net 191 "unconnected-(J18C-LA31_N-PadG34)")
			(pinfunction "LA31_N")
			(pintype "passive+no_connect")
		)
		(pad "G35" smd circle
			(at -18.415 -1.905 90)
			(size 0.64 0.64)
			(layers "F.Cu" "F.Mask")
			(net 1 "GND")
			(pinfunction "GND")
			(pintype "passive")
		)
		(pad "G36" smd circle
			(at -19.685 -1.905 90)
			(size 0.64 0.64)
			(layers "F.Cu" "F.Mask")
			(net 192 "unconnected-(J18C-LA33_P-PadG36)")
			(pinfunction "LA33_P")
			(pintype "passive+no_connect")
		)
		(pad "G37" smd circle
			(at -20.956 -1.905 90)
			(size 0.64 0.64)
			(layers "F.Cu" "F.Mask")
			(net 193 "unconnected-(J18C-LA33_N-PadG37)")
			(pinfunction "LA33_N")
			(pintype "passive+no_connect")
		)
		(pad "G38" smd circle
			(at -22.226 -1.905 90)
			(size 0.64 0.64)
			(layers "F.Cu" "F.Mask")
			(net 1 "GND")
			(pinfunction "GND")
			(pintype "passive")
		)
		(pad "G39" smd circle
			(at -23.497 -1.905 90)
			(size 0.64 0.64)
			(layers "F.Cu" "F.Mask")
			(net 152 "unconnected-(J18A-VADJ-PadE39)")
			(pinfunction "VADJ")
			(pintype "passive+no_connect")
		)
		(pad "G40" smd circle
			(at -24.767 -1.905 90)
			(size 0.64 0.64)
			(layers "F.Cu" "F.Mask")
			(net 1 "GND")
			(pinfunction "GND")
			(pintype "passive")
		)
		(pad "H01" smd circle
			(at 24.765 -3.176 90)
			(size 0.64 0.64)
			(layers "F.Cu" "F.Mask")
			(net 194 "Net-(J18A-VREF_A_M2C)")
			(pinfunction "VREF_A_M2C")
			(pintype "passive")
		)
		(pad "H02" smd circle
			(at 23.495 -3.176 90)
			(size 0.64 0.64)
			(layers "F.Cu" "F.Mask")
			(net 696 "/FMC+ HSPC/FMC.PRSNT_M2C")
			(pinfunction "PRSNT_M2C_L")
			(pintype "passive")
		)
		(pad "H03" smd circle
			(at 22.225 -3.176 90)
			(size 0.64 0.64)
			(layers "F.Cu" "F.Mask")
			(net 1 "GND")
			(pinfunction "GND")
			(pintype "passive")
		)
		(pad "H04" smd circle
			(at 20.954 -3.176 90)
			(size 0.64 0.64)
			(layers "F.Cu" "F.Mask")
			(net 195 "unconnected-(J18F-CLK0_M2C_P-PadH04)")
			(pinfunction "CLK0_M2C_P")
			(pintype "passive+no_connect")
		)
		(pad "H05" smd circle
			(at 19.684 -3.176 90)
			(size 0.64 0.64)
			(layers "F.Cu" "F.Mask")
			(net 196 "unconnected-(J18F-CLK0_M2C_N-PadH05)")
			(pinfunction "CLK0_M2C_N")
			(pintype "passive+no_connect")
		)
		(pad "H06" smd circle
			(at 18.414 -3.176 90)
			(size 0.64 0.64)
			(layers "F.Cu" "F.Mask")
			(net 1 "GND")
			(pinfunction "GND")
			(pintype "passive")
		)
		(pad "H07" smd circle
			(at 17.144 -3.176 90)
			(size 0.64 0.64)
			(layers "F.Cu" "F.Mask")
			(net 197 "unconnected-(J18C-LA02_P-PadH07)")
			(pinfunction "LA02_P")
			(pintype "passive+no_connect")
		)
		(pad "H08" smd circle
			(at 15.874 -3.176 90)
			(size 0.64 0.64)
			(layers "F.Cu" "F.Mask")
			(net 198 "unconnected-(J18C-LA02_N-PadH08)")
			(pinfunction "LA02_N")
			(pintype "passive+no_connect")
		)
		(pad "H09" smd circle
			(at 14.605 -3.176 90)
			(size 0.64 0.64)
			(layers "F.Cu" "F.Mask")
			(net 1 "GND")
			(pinfunction "GND")
			(pintype "passive")
		)
		(pad "H10" smd circle
			(at 13.335 -3.176 90)
			(size 0.64 0.64)
			(layers "F.Cu" "F.Mask")
			(net 199 "unconnected-(J18C-LA04_P-PadH10)")
			(pinfunction "LA04_P")
			(pintype "passive+no_connect")
		)
		(pad "H11" smd circle
			(at 12.063 -3.176 90)
			(size 0.64 0.64)
			(layers "F.Cu" "F.Mask")
			(net 200 "unconnected-(J18C-LA04_N-PadH11)")
			(pinfunction "LA04_N")
			(pintype "passive+no_connect")
		)
		(pad "H12" smd circle
			(at 10.794 -3.176 90)
			(size 0.64 0.64)
			(layers "F.Cu" "F.Mask")
			(net 1 "GND")
			(pinfunction "GND")
			(pintype "passive")
		)
		(pad "H13" smd circle
			(at 9.525 -3.176 90)
			(size 0.64 0.64)
			(layers "F.Cu" "F.Mask")
			(net 201 "unconnected-(J18C-LA07_P-PadH13)")
			(pinfunction "LA07_P")
			(pintype "passive+no_connect")
		)
		(pad "H14" smd circle
			(at 8.255 -3.176 90)
			(size 0.64 0.64)
			(layers "F.Cu" "F.Mask")
			(net 202 "unconnected-(J18C-LA07_N-PadH14)")
			(pinfunction "LA07_N")
			(pintype "passive+no_connect")
		)
		(pad "H15" smd circle
			(at 6.985 -3.176 90)
			(size 0.64 0.64)
			(layers "F.Cu" "F.Mask")
			(net 1 "GND")
			(pinfunction "GND")
			(pintype "passive")
		)
		(pad "H16" smd circle
			(at 5.714 -3.176 90)
			(size 0.64 0.64)
			(layers "F.Cu" "F.Mask")
			(net 464 "/FMC+ HSPC/FMC.IO4_P")
			(pinfunction "LA11_P")
			(pintype "passive")
		)
		(pad "H17" smd circle
			(at 4.445 -3.176 90)
			(size 0.64 0.64)
			(layers "F.Cu" "F.Mask")
			(net 460 "/FMC+ HSPC/FMC.IO4_N")
			(pinfunction "LA11_N")
			(pintype "passive")
		)
		(pad "H18" smd circle
			(at 3.173 -3.176 90)
			(size 0.64 0.64)
			(layers "F.Cu" "F.Mask")
			(net 1 "GND")
			(pinfunction "GND")
			(pintype "passive")
		)
		(pad "H19" smd circle
			(at 1.904 -3.176 90)
			(size 0.64 0.64)
			(layers "F.Cu" "F.Mask")
			(net 449 "/FMC+ HSPC/FMC.IO3_P")
			(pinfunction "LA15_P")
			(pintype "passive")
		)
		(pad "H20" smd circle
			(at 0.633 -3.176 90)
			(size 0.64 0.64)
			(layers "F.Cu" "F.Mask")
			(net 446 "/FMC+ HSPC/FMC.IO3_N")
			(pinfunction "LA15_N")
			(pintype "passive")
		)
		(pad "H21" smd circle
			(at -0.635 -3.176 90)
			(size 0.64 0.64)
			(layers "F.Cu" "F.Mask")
			(net 1 "GND")
			(pinfunction "GND")
			(pintype "passive")
		)
		(pad "H22" smd circle
			(at -1.905 -3.176 90)
			(size 0.64 0.64)
			(layers "F.Cu" "F.Mask")
			(net 413 "/FMC+ HSPC/FMC.IO19_P")
			(pinfunction "LA19_P")
			(pintype "passive")
		)
		(pad "H23" smd circle
			(at -3.176 -3.176 90)
			(size 0.64 0.64)
			(layers "F.Cu" "F.Mask")
			(net 409 "/FMC+ HSPC/FMC.IO19_N")
			(pinfunction "LA19_N")
			(pintype "passive")
		)
		(pad "H24" smd circle
			(at -4.446 -3.176 90)
			(size 0.64 0.64)
			(layers "F.Cu" "F.Mask")
			(net 1 "GND")
			(pinfunction "GND")
			(pintype "passive")
		)
		(pad "H25" smd circle
			(at -5.715 -3.176 90)
			(size 0.64 0.64)
			(layers "F.Cu" "F.Mask")
			(net 400 "/FMC+ HSPC/FMC.IO10_P")
			(pinfunction "LA21_P")
			(pintype "passive")
		)
		(pad "H26" smd circle
			(at -6.986 -3.176 90)
			(size 0.64 0.64)
			(layers "F.Cu" "F.Mask")
			(net 396 "/FMC+ HSPC/FMC.IO10_N")
			(pinfunction "LA21_N")
			(pintype "passive")
		)
		(pad "H27" smd circle
			(at -8.257 -3.176 90)
			(size 0.64 0.64)
			(layers "F.Cu" "F.Mask")
			(net 1 "GND")
			(pinfunction "GND")
			(pintype "passive")
		)
		(pad "H28" smd circle
			(at -9.526 -3.176 90)
			(size 0.64 0.64)
			(layers "F.Cu" "F.Mask")
			(net 387 "/FMC+ HSPC/FMC.IO7_P")
			(pinfunction "LA24_P")
			(pintype "passive")
		)
		(pad "H29" smd circle
			(at -10.795 -3.176 90)
			(size 0.64 0.64)
			(layers "F.Cu" "F.Mask")
			(net 384 "/FMC+ HSPC/FMC.IO7_N")
			(pinfunction "LA24_N")
			(pintype "passive")
		)
		(pad "H30" smd circle
			(at -12.065 -3.176 90)
			(size 0.64 0.64)
			(layers "F.Cu" "F.Mask")
			(net 1 "GND")
			(pinfunction "GND")
			(pintype "passive")
		)
		(pad "H31" smd circle
			(at -13.337 -3.176 90)
			(size 0.64 0.64)
			(layers "F.Cu" "F.Mask")
			(net 642 "/FMC+ HSPC/FMC.IO22_P")
			(pinfunction "LA28_P")
			(pintype "passive")
		)
		(pad "H32" smd circle
			(at -14.606 -3.176 90)
			(size 0.64 0.64)
			(layers "F.Cu" "F.Mask")
			(net 634 "/FMC+ HSPC/FMC.IO22_N")
			(pinfunction "LA28_N")
			(pintype "passive")
		)
		(pad "H33" smd circle
			(at -15.875 -3.176 90)
			(size 0.64 0.64)
			(layers "F.Cu" "F.Mask")
			(net 1 "GND")
			(pinfunction "GND")
			(pintype "passive")
		)
		(pad "H34" smd circle
			(at -17.145 -3.176 90)
			(size 0.64 0.64)
			(layers "F.Cu" "F.Mask")
			(net 203 "unconnected-(J18C-LA30_P-PadH34)")
			(pinfunction "LA30_P")
			(pintype "passive+no_connect")
		)
		(pad "H35" smd circle
			(at -18.415 -3.176 90)
			(size 0.64 0.64)
			(layers "F.Cu" "F.Mask")
			(net 204 "unconnected-(J18C-LA30_N-PadH35)")
			(pinfunction "LA30_N")
			(pintype "passive+no_connect")
		)
		(pad "H36" smd circle
			(at -19.685 -3.176 90)
			(size 0.64 0.64)
			(layers "F.Cu" "F.Mask")
			(net 1 "GND")
			(pinfunction "GND")
			(pintype "passive")
		)
		(pad "H37" smd circle
			(at -20.956 -3.176 90)
			(size 0.64 0.64)
			(layers "F.Cu" "F.Mask")
			(net 205 "unconnected-(J18C-LA32_P-PadH37)")
			(pinfunction "LA32_P")
			(pintype "passive+no_connect")
		)
		(pad "H38" smd circle
			(at -22.226 -3.176 90)
			(size 0.64 0.64)
			(layers "F.Cu" "F.Mask")
			(net 206 "unconnected-(J18C-LA32_N-PadH38)")
			(pinfunction "LA32_N")
			(pintype "passive+no_connect")
		)
		(pad "H39" smd circle
			(at -23.497 -3.176 90)
			(size 0.64 0.64)
			(layers "F.Cu" "F.Mask")
			(net 1 "GND")
			(pinfunction "GND")
			(pintype "passive")
		)
		(pad "H40" smd circle
			(at -24.767 -3.176 90)
			(size 0.64 0.64)
			(layers "F.Cu" "F.Mask")
			(net 152 "unconnected-(J18A-VADJ-PadE39)")
			(pinfunction "VADJ")
			(pintype "passive+no_connect")
		)
		(pad "J01" smd circle
			(at 24.765 -4.446 90)
			(size 0.64 0.64)
			(layers "F.Cu" "F.Mask")
			(net 1 "GND")
			(pinfunction "GND")
			(pintype "passive")
		)
		(pad "J02" smd circle
			(at 23.495 -4.446 90)
			(size 0.64 0.64)
			(layers "F.Cu" "F.Mask")
			(net 597 "/FMC+ HSPC/GTR_REFCLK3_R_P")
			(pinfunction "CLK3_BIDIR_P")
			(pintype "passive")
		)
		(pad "J03" smd circle
			(at 22.225 -4.446 90)
			(size 0.64 0.64)
			(layers "F.Cu" "F.Mask")
			(net 599 "/FMC+ HSPC/GTR_REFCLK3_R_N")
			(pinfunction "CLK3_BIDIR_N")
			(pintype "passive")
		)
		(pad "J04" smd circle
			(at 20.954 -4.446 90)
			(size 0.64 0.64)
			(layers "F.Cu" "F.Mask")
			(net 1 "GND")
			(pinfunction "GND")
			(pintype "passive")
		)
		(pad "J05" smd circle
			(at 19.684 -4.446 90)
			(size 0.64 0.64)
			(layers "F.Cu" "F.Mask")
			(net 1 "GND")
			(pinfunction "GND")
			(pintype "passive")
		)
		(pad "J06" smd circle
			(at 18.414 -4.446 90)
			(size 0.64 0.64)
			(layers "F.Cu" "F.Mask")
			(net 643 "/FMC+ HSPC/FMC.IO15_P")
			(pinfunction "HA03_P")
			(pintype "passive")
		)
		(pad "J07" smd circle
			(at 17.144 -4.446 90)
			(size 0.64 0.64)
			(layers "F.Cu" "F.Mask")
			(net 641 "/FMC+ HSPC/FMC.IO15_N")
			(pinfunction "HA03_N")
			(pintype "passive")
		)
		(pad "J08" smd circle
			(at 15.874 -4.446 90)
			(size 0.64 0.64)
			(layers "F.Cu" "F.Mask")
			(net 1 "GND")
			(pinfunction "GND")
			(pintype "passive")
		)
		(pad "J09" smd circle
			(at 14.605 -4.446 90)
			(size 0.64 0.64)
			(layers "F.Cu" "F.Mask")
			(net 254 "/FMC+ HSPC/FMC.IO18_P")
			(pinfunction "HA07_P")
			(pintype "passive")
		)
		(pad "J10" smd circle
			(at 13.335 -4.446 90)
			(size 0.64 0.64)
			(layers "F.Cu" "F.Mask")
			(net 241 "/FMC+ HSPC/FMC.IO18_N")
			(pinfunction "HA07_N")
			(pintype "passive")
		)
		(pad "J11" smd circle
			(at 12.063 -4.446 90)
			(size 0.64 0.64)
			(layers "F.Cu" "F.Mask")
			(net 1 "GND")
			(pinfunction "GND")
			(pintype "passive")
		)
		(pad "J12" smd circle
			(at 10.794 -4.446 90)
			(size 0.64 0.64)
			(layers "F.Cu" "F.Mask")
			(net 445 "/FMC+ HSPC/FMC.IO23_P")
			(pinfunction "HA11_P")
			(pintype "passive")
		)
		(pad "J13" smd circle
			(at 9.525 -4.446 90)
			(size 0.64 0.64)
			(layers "F.Cu" "F.Mask")
			(net 444 "/FMC+ HSPC/FMC.IO23_N")
			(pinfunction "HA11_N")
			(pintype "passive")
		)
		(pad "J14" smd circle
			(at 8.255 -4.446 90)
			(size 0.64 0.64)
			(layers "F.Cu" "F.Mask")
			(net 1 "GND")
			(pinfunction "GND")
			(pintype "passive")
		)
		(pad "J15" smd circle
			(at 6.985 -4.446 90)
			(size 0.64 0.64)
			(layers "F.Cu" "F.Mask")
			(net 207 "unconnected-(J18D-HA14_P-PadJ15)")
			(pinfunction "HA14_P")
			(pintype "passive+no_connect")
		)
		(pad "J16" smd circle
			(at 5.714 -4.446 90)
			(size 0.64 0.64)
			(layers "F.Cu" "F.Mask")
			(net 208 "unconnected-(J18D-HA14_N-PadJ16)")
			(pinfunction "HA14_N")
			(pintype "passive+no_connect")
		)
		(pad "J17" smd circle
			(at 4.445 -4.446 90)
			(size 0.64 0.64)
			(layers "F.Cu" "F.Mask")
			(net 1 "GND")
			(pinfunction "GND")
			(pintype "passive")
		)
		(pad "J18" smd circle
			(at 3.173 -4.446 90)
			(size 0.64 0.64)
			(layers "F.Cu" "F.Mask")
			(net 441 "/FMC+ HSPC/FMC.IO5_P")
			(pinfunction "HA18_P")
			(pintype "passive")
		)
		(pad "J19" smd circle
			(at 1.904 -4.446 90)
			(size 0.64 0.64)
			(layers "F.Cu" "F.Mask")
			(net 440 "/FMC+ HSPC/FMC.IO5_N")
			(pinfunction "HA18_N")
			(pintype "passive")
		)
		(pad "J20" smd circle
			(at 0.633 -4.446 90)
			(size 0.64 0.64)
			(layers "F.Cu" "F.Mask")
			(net 1 "GND")
			(pinfunction "GND")
			(pintype "passive")
		)
		(pad "J21" smd circle
			(at -0.635 -4.446 90)
			(size 0.64 0.64)
			(layers "F.Cu" "F.Mask")
			(net 354 "/FMC+ HSPC/FMC.IO12_P")
			(pinfunction "HA22_P")
			(pintype "passive")
		)
		(pad "J22" smd circle
			(at -1.905 -4.446 90)
			(size 0.64 0.64)
			(layers "F.Cu" "F.Mask")
			(net 353 "/FMC+ HSPC/FMC.IO12_N")
			(pinfunction "HA22_N")
			(pintype "passive")
		)
		(pad "J23" smd circle
			(at -3.176 -4.446 90)
			(size 0.64 0.64)
			(layers "F.Cu" "F.Mask")
			(net 1 "GND")
			(pinfunction "GND")
			(pintype "passive")
		)
		(pad "J24" smd circle
			(at -4.446 -4.446 90)
			(size 0.64 0.64)
			(layers "F.Cu" "F.Mask")
			(net 352 "/FMC+ HSPC/FMC.IO14_P")
			(pinfunction "HB01_P")
			(pintype "passive")
		)
		(pad "J25" smd circle
			(at -5.715 -4.446 90)
			(size 0.64 0.64)
			(layers "F.Cu" "F.Mask")
			(net 351 "/FMC+ HSPC/FMC.IO14_N")
			(pinfunction "HB01_N")
			(pintype "passive")
		)
		(pad "J26" smd circle
			(at -6.986 -4.446 90)
			(size 0.64 0.64)
			(layers "F.Cu" "F.Mask")
			(net 1 "GND")
			(pinfunction "GND")
			(pintype "passive")
		)
		(pad "J27" smd circle
			(at -8.257 -4.446 90)
			(size 0.64 0.64)
			(layers "F.Cu" "F.Mask")
			(net 350 "/FMC+ HSPC/FMC.IO24_P")
			(pinfunction "HB07_P")
			(pintype "passive")
		)
		(pad "J28" smd circle
			(at -9.526 -4.446 90)
			(size 0.64 0.64)
			(layers "F.Cu" "F.Mask")
			(net 349 "/FMC+ HSPC/FMC.IO24_N")
			(pinfunction "HB07_N")
			(pintype "passive")
		)
		(pad "J29" smd circle
			(at -10.795 -4.446 90)
			(size 0.64 0.64)
			(layers "F.Cu" "F.Mask")
			(net 1 "GND")
			(pinfunction "GND")
			(pintype "passive")
		)
		(pad "J30" smd circle
			(at -12.065 -4.446 90)
			(size 0.64 0.64)
			(layers "F.Cu" "F.Mask")
			(net 209 "unconnected-(J18E-HB11_P-PadJ30)")
			(pinfunction "HB11_P")
			(pintype "passive+no_connect")
		)
		(pad "J31" smd circle
			(at -13.337 -4.446 90)
			(size 0.64 0.64)
			(layers "F.Cu" "F.Mask")
			(net 210 "unconnected-(J18E-HB11_N-PadJ31)")
			(pinfunction "HB11_N")
			(pintype "passive+no_connect")
		)
		(pad "J32" smd circle
			(at -14.606 -4.446 90)
			(size 0.64 0.64)
			(layers "F.Cu" "F.Mask")
			(net 1 "GND")
			(pinfunction "GND")
			(pintype "passive")
		)
		(pad "J33" smd circle
			(at -15.875 -4.446 90)
			(size 0.64 0.64)
			(layers "F.Cu" "F.Mask")
			(net 211 "unconnected-(J18E-HB15_P-PadJ33)")
			(pinfunction "HB15_P")
			(pintype "passive+no_connect")
		)
		(pad "J34" smd circle
			(at -17.145 -4.446 90)
			(size 0.64 0.64)
			(layers "F.Cu" "F.Mask")
			(net 212 "unconnected-(J18E-HB15_N-PadJ34)")
			(pinfunction "HB15_N")
			(pintype "passive+no_connect")
		)
	)
)
